# T6G (Grand Teton) — schematic netlist excerpt (pin names and nets, part order shuffled) for the footprints in the layout excerpt that follows; sources: Cadence DE-HDL packaged netlist, KiCad conversion of 04192023_DAF0TMB3IC0_F0TG_MB_C_brd_V02_OCP.brd

R6783  Q_RES  33 5% CHIP  pkg 0402LF  page 151 : A = SMB_MUX_RT_ROM_R1_SDA ; B = SMB_HOST_CLK_3V3AUX_SDA_R1
C834  Q_CAP_DIFFBUS  DIFF BUS_0.22UF 6.3V 20% X6S  pkg C0201  page 65 : \1\ = P5E_CPU1_P0_TX_C_DN<1> ; \2\ = P5E_CPU1_P0_TX_DN<1>
PC203  Q_CAP  2.2UF 10V 10% X6S  pkg C0402  page 208 : A = PVDD11_S3_P0_VCC1 ; B = GND

(kicad_pcb
	(version 20260206)
	(generator "pcbnew")
	(generator_version "10.0")
	(general
		(thickness 1.6)
		(legacy_teardrops no)
	)
	(paper "A4")
	(title_block
		(title "04192023_DAF0TMB3IC0_F0TG_MB_C_brd_V02_OCP.brd")
		(comment 1 "Grand Teton / footprints 3816-3818 of 8354")
	)
	(layers
		(0 "F.Cu" signal "TOP")
		(4 "In1.Cu" signal "GND")
		(6 "In2.Cu" signal "IN1")
		(8 "In3.Cu" signal "GND1")
		(10 "In4.Cu" signal "IN2")
		(12 "In5.Cu" signal "GND2")
		(14 "In6.Cu" signal "IN3")
		(16 "In7.Cu" signal "GND3")
		(18 "In8.Cu" signal "VCC")
		(20 "In9.Cu" signal "VCC1")
		(22 "In10.Cu" signal "GND4")
		(24 "In11.Cu" signal "IN4")
		(26 "In12.Cu" signal "GND5")
		(28 "In13.Cu" signal "IN5")
		(30 "In14.Cu" signal "GND6")
		(32 "In15.Cu" signal "IN6")
		(34 "In16.Cu" signal "GND7")
		(2 "B.Cu" signal "BOTTOM")
		(9 "F.Adhes" user "F.Adhesive")
		(11 "B.Adhes" user "B.Adhesive")
		(13 "F.Paste" user "Package Geometry/Pastemask Top")
		(15 "B.Paste" user "Package Geometry/Pastemask Bottom")
		(5 "F.SilkS" user "Ref Des/Silkscreen Top")
		(7 "B.SilkS" user "Ref Des/Silkscreen Bottom")
		(1 "F.Mask" user "Board Geometry/Soldermask Top")
		(3 "B.Mask" user "Board Geometry/Soldermask Bottom")
		(17 "Dwgs.User" user "User.Drawings")
		(19 "Cmts.User" user "User.Comments")
		(21 "Eco1.User" user "User.Eco1")
		(23 "Eco2.User" user "User.Eco2")
		(25 "Edge.Cuts" user "Board Geometry/Outline")
		(27 "Margin" user)
		(31 "F.CrtYd" user "Package Geometry/Place Bound Top")
		(29 "B.CrtYd" user "Package Geometry/Place Bound Bottom")
		(35 "F.Fab" user "Ref Des/Assembly Top")
		(33 "B.Fab" user "Ref Des/Assembly Bottom")
	)
	(footprint ""
		(layer "F.Cu")
		(at 277.581106 -414.966404)
		(property "Reference" "R6783"
			(at 0 0 0)
			(layer "F.SilkS")
			(hide yes)
			(effects
				(font
					(size 1.27 1.27)
				)
			)
		)
		(property "Value" ""
			(at 0 0 0)
			(layer "F.Fab")
			(effects
				(font
					(size 1.27 1.27)
				)
			)
		)
		(duplicate_pad_numbers_are_jumpers no)
		(fp_line
			(start -0.7874 -0.4064)
			(end 0.7874 -0.4064)
			(stroke
				(width 0.1524)
				(type default)
			)
			(layer "F.SilkS")
		)
		(fp_line
			(start -0.7874 0.4064)
			(end -0.7874 -0.4064)
			(stroke
				(width 0.1524)
				(type default)
			)
			(layer "F.SilkS")
		)
		(fp_line
			(start 0.7874 -0.4064)
			(end 0.7874 0.4064)
			(stroke
				(width 0.1524)
				(type default)
			)
			(layer "F.SilkS")
		)
		(fp_line
			(start 0.7874 0.4064)
			(end -0.7874 0.4064)
			(stroke
				(width 0.1524)
				(type default)
			)
			(layer "F.SilkS")
		)
		(fp_line
			(start -0.67945 -0.305054)
			(end -0.12065 -0.305054)
			(stroke
				(width 0.1)
				(type default)
			)
			(layer "F.Fab")
		)
		(fp_line
			(start -0.67945 0.3048)
			(end -0.67945 -0.305054)
			(stroke
				(width 0.1)
				(type default)
			)
			(layer "F.Fab")
		)
		(fp_line
			(start -0.12065 -0.305054)
			(end -0.12065 -0.2794)
			(stroke
				(width 0.1)
				(type default)
			)
			(layer "F.Fab")
		)
		(fp_line
			(start -0.12065 -0.2794)
			(end 0.12065 -0.2794)
			(stroke
				(width 0.1)
				(type default)
			)
			(layer "F.Fab")
		)
		(fp_line
			(start -0.12065 0.2794)
			(end -0.12065 0.3048)
			(stroke
				(width 0.1)
				(type default)
			)
			(layer "F.Fab")
		)
		(fp_line
			(start -0.12065 0.3048)
			(end -0.67945 0.3048)
			(stroke
				(width 0.1)
				(type default)
			)
			(layer "F.Fab")
		)
		(fp_line
			(start 0.120396 0.2794)
			(end -0.12065 0.2794)
			(stroke
				(width 0.1)
				(type default)
			)
			(layer "F.Fab")
		)
		(fp_line
			(start 0.120396 0.3048)
			(end 0.120396 0.2794)
			(stroke
				(width 0.1)
				(type default)
			)
			(layer "F.Fab")
		)
		(fp_line
			(start 0.12065 -0.3048)
			(end 0.67945 -0.3048)
			(stroke
				(width 0.1)
				(type default)
			)
			(layer "F.Fab")
		)
		(fp_line
			(start 0.12065 -0.2794)
			(end 0.12065 -0.3048)
			(stroke
				(width 0.1)
				(type default)
			)
			(layer "F.Fab")
		)
		(fp_line
			(start 0.67945 -0.3048)
			(end 0.67945 0.3048)
			(stroke
				(width 0.1)
				(type default)
			)
			(layer "F.Fab")
		)
		(fp_line
			(start 0.67945 0.3048)
			(end 0.120396 0.3048)
			(stroke
				(width 0.1)
				(type default)
			)
			(layer "F.Fab")
		)
		(pad "1" smd circle
			(at -0.40005 0)
			(size 0 0)
			(layers "F.Cu" "F.Mask" "F.Paste")
			(net "SMB_MUX_RT_ROM_R1_SDA")
		)
		(pad "2" smd circle
			(at 0.40005 0)
			(size 0 0)
			(layers "F.Cu" "F.Mask" "F.Paste")
			(net "SMB_HOST_CLK_3V3AUX_SDA_R1")
		)
	)
	(footprint ""
		(layer "F.Cu")
		(at 419.96106 -353.78009 90)
		(property "Reference" "PC203"
			(at 0 0 90)
			(layer "F.SilkS")
			(hide yes)
			(effects
				(font
					(size 1.27 1.27)
				)
			)
		)
		(property "Value" ""
			(at 0 0 90)
			(layer "F.Fab")
			(effects
				(font
					(size 1.27 1.27)
				)
			)
		)
		(duplicate_pad_numbers_are_jumpers no)
		(fp_line
			(start 0.7874 -0.4064)
			(end 0.7874 0.4064)
			(stroke
				(width 0.1524)
				(type default)
			)
			(layer "F.SilkS")
		)
		(fp_line
			(start -0.7874 -0.4064)
			(end 0.7874 -0.4064)
			(stroke
				(width 0.1524)
				(type default)
			)
			(layer "F.SilkS")
		)
		(fp_line
			(start 0.7874 0.4064)
			(end 0.37211 0.4064)
			(stroke
				(width 0.1524)
				(type default)
			)
			(layer "F.SilkS")
		)
		(fp_line
			(start -0.18669 0.4064)
			(end -0.7874 0.4064)
			(stroke
				(width 0.1524)
				(type default)
			)
			(layer "F.SilkS")
		)
		(fp_line
			(start -0.7874 0.4064)
			(end -0.7874 -0.4064)
			(stroke
				(width 0.1524)
				(type default)
			)
			(layer "F.SilkS")
		)
		(fp_line
			(start -0.12065 -0.305054)
			(end -0.12065 -0.2794)
			(stroke
				(width 0.1)
				(type default)
			)
			(layer "F.Fab")
		)
		(fp_line
			(start -0.67945 -0.305054)
			(end -0.12065 -0.305054)
			(stroke
				(width 0.1)
				(type default)
			)
			(layer "F.Fab")
		)
		(fp_line
			(start 0.67945 -0.3048)
			(end 0.67945 0.3048)
			(stroke
				(width 0.1)
				(type default)
			)
			(layer "F.Fab")
		)
		(fp_line
			(start 0.12065 -0.3048)
			(end 0.67945 -0.3048)
			(stroke
				(width 0.1)
				(type default)
			)
			(layer "F.Fab")
		)
		(fp_line
			(start 0.12065 -0.2794)
			(end 0.12065 -0.3048)
			(stroke
				(width 0.1)
				(type default)
			)
			(layer "F.Fab")
		)
		(fp_line
			(start -0.12065 -0.2794)
			(end 0.12065 -0.2794)
			(stroke
				(width 0.1)
				(type default)
			)
			(layer "F.Fab")
		)
		(fp_line
			(start 0.120396 0.2794)
			(end -0.12065 0.2794)
			(stroke
				(width 0.1)
				(type default)
			)
			(layer "F.Fab")
		)
		(fp_line
			(start -0.12065 0.2794)
			(end -0.12065 0.3048)
			(stroke
				(width 0.1)
				(type default)
			)
			(layer "F.Fab")
		)
		(fp_line
			(start 0.67945 0.3048)
			(end 0.120396 0.3048)
			(stroke
				(width 0.1)
				(type default)
			)
			(layer "F.Fab")
		)
		(fp_line
			(start 0.120396 0.3048)
			(end 0.120396 0.2794)
			(stroke
				(width 0.1)
				(type default)
			)
			(layer "F.Fab")
		)
		(fp_line
			(start -0.12065 0.3048)
			(end -0.67945 0.3048)
			(stroke
				(width 0.1)
				(type default)
			)
			(layer "F.Fab")
		)
		(fp_line
			(start -0.67945 0.3048)
			(end -0.67945 -0.305054)
			(stroke
				(width 0.1)
				(type default)
			)
			(layer "F.Fab")
		)
		(pad "1" smd circle
			(at -0.40005 0 90)
			(size 0 0)
			(layers "F.Cu" "F.Mask" "F.Paste")
			(net "PVDD11_S3_P0_VCC1")
		)
		(pad "2" smd circle
			(at 0.40005 0 90)
			(size 0 0)
			(layers "F.Cu" "F.Mask" "F.Paste")
			(net "GND")
		)
	)
	(footprint ""
		(layer "F.Cu")
		(at 42.967402 -376.85726 180)
		(property "Reference" "C834"
			(at 0 0 180)
			(layer "F.SilkS")
			(hide yes)
			(effects
				(font
					(size 1.27 1.27)
				)
			)
		)
		(property "Value" ""
			(at 0 0 180)
			(layer "F.Fab")
			(effects
				(font
					(size 1.27 1.27)
				)
			)
		)
		(duplicate_pad_numbers_are_jumpers no)
		(fp_line
			(start 0.299974 0.150114)
			(end -0.299974 0.150114)
			(stroke
				(width 0.1)
				(type default)
			)
			(layer "F.Fab")
		)
		(fp_line
			(start 0.299974 -0.150114)
			(end 0.299974 0.150114)
			(stroke
				(width 0.1)
				(type default)
			)
			(layer "F.Fab")
		)
		(fp_line
			(start -0.299974 0.150114)
			(end -0.299974 -0.150114)
			(stroke
				(width 0.1)
				(type default)
			)
			(layer "F.Fab")
		)
		(fp_line
			(start -0.299974 -0.150114)
			(end 0.299974 -0.150114)
			(stroke
				(width 0.1)
				(type default)
			)
			(layer "F.Fab")
		)
		(pad "1" smd rect
			(at -0.2667 0 180)
			(size 0.3048 0.381)
			(layers "F.Cu" "F.Mask" "F.Paste")
			(net "P5E_CPU1_P0_TX_C_DN<1>")
		)
		(pad "2" smd rect
			(at 0.2667 0 180)
			(size 0.3048 0.381)
			(layers "F.Cu" "F.Mask" "F.Paste")
			(net "P5E_CPU1_P0_TX_DN<1>")
		)
	)
)
